(kicad_pcb
	(version 20241229)
	(generator "pcbnew")
	(generator_version "9.0")
	(general
		(thickness 1.294)
		(legacy_teardrops no)
	)
	(paper "A3")
	(title_block
		(title "Kintex 410T devboard")
		(date "2024-04-03")
		(rev "1.1.2")
		(comment 9 "footprints 290-293 of 975")
	)
	(layers
		(0 "F.Cu" mixed)
		(4 "In1.Cu" power)
		(6 "In2.Cu" power)
		(8 "In3.Cu" mixed)
		(10 "In4.Cu" power)
		(12 "In5.Cu" mixed)
		(14 "In6.Cu" power)
		(16 "In7.Cu" mixed)
		(18 "In8.Cu" power)
		(2 "B.Cu" mixed)
		(9 "F.Adhes" user "F.Adhesive")
		(11 "B.Adhes" user "B.Adhesive")
		(13 "F.Paste" user)
		(15 "B.Paste" user)
		(5 "F.SilkS" user "F.Silkscreen")
		(7 "B.SilkS" user "B.Silkscreen")
		(1 "F.Mask" user)
		(3 "B.Mask" user)
		(17 "Dwgs.User" user "User.Drawings")
		(19 "Cmts.User" user "User.Comments")
		(21 "Eco1.User" user "User.Eco1")
		(23 "Eco2.User" user "User.Eco2")
		(25 "Edge.Cuts" user)
		(27 "Margin" user)
		(31 "F.CrtYd" user "F.Courtyard")
		(29 "B.CrtYd" user "B.Courtyard")
		(35 "F.Fab" user)
		(33 "B.Fab" user)
	)
	(footprint "antmicro-footprints:C_0402_1005Metric"
		(layer "F.Cu")
		(at 243.325 132.9 -90)
		(descr "Capacitor SMD 0402")
		(tags "capacitor SMD 0402")
		(property "Reference" "C241"
			(at 3.925 0.5 270)
			(layer "F.SilkS")
			(effects
				(font
					(size 0.7 0.7)
					(thickness 0.15)
				)
				(justify left bottom)
			)
		)
		(property "Value" "C_100n_0402"
			(at 0 1.169 270)
			(layer "F.Fab")
			(effects
				(font
					(size 0.7 0.7)
					(thickness 0.15)
				)
				(justify left bottom)
			)
		)
		(property "Description" "SMD Multilayer Ceramic Capacitor, 0.1 µF, 50 V, 0402 [1005 Metric], ± 10%, X5R, GRM Series"
			(at 0 0 270)
			(layer "F.Fab")
			(hide yes)
			(effects
				(font
					(size 1.27 1.27)
					(thickness 0.15)
				)
			)
		)
		(property "Author" "Antmicro"
			(at 110.425 376.225 0)
			(layer "F.Fab")
			(hide yes)
			(effects
				(font
					(size 1 1)
					(thickness 0.15)
				)
			)
		)
		(property "Dielectric" "X5R"
			(at 110.425 376.225 0)
			(layer "F.Fab")
			(hide yes)
			(effects
				(font
					(size 1 1)
					(thickness 0.15)
				)
			)
		)
		(property "License" "Apache-2.0"
			(at 110.425 376.225 0)
			(layer "F.Fab")
			(hide yes)
			(effects
				(font
					(size 1 1)
					(thickness 0.15)
				)
			)
		)
		(property "MPN" "GRM155R61H104KE14D"
			(at 110.425 376.225 0)
			(layer "F.Fab")
			(hide yes)
			(effects
				(font
					(size 1 1)
					(thickness 0.15)
				)
			)
		)
		(property "Manufacturer" "Murata"
			(at 110.425 376.225 0)
			(layer "F.Fab")
			(hide yes)
			(effects
				(font
					(size 1 1)
					(thickness 0.15)
				)
			)
		)
		(property "Val" "100n"
			(at 110.425 376.225 0)
			(layer "F.Fab")
			(hide yes)
			(effects
				(font
					(size 1 1)
					(thickness 0.15)
				)
			)
		)
		(property "Voltage" "50V"
			(at 110.425 376.225 0)
			(layer "F.Fab")
			(hide yes)
			(effects
				(font
					(size 1 1)
					(thickness 0.15)
				)
			)
		)
		(sheetname "USB PHY")
		(sheetfile "usb-phy.kicad_sch")
		(attr smd)
		(fp_rect
			(start -0.925 -0.47)
			(end 0.925 0.47)
			(stroke
				(width 0.05)
				(type default)
			)
			(fill no)
			(layer "F.CrtYd")
		)
		(fp_line
			(start -0.494 0.248)
			(end -0.494 -0.25)
			(stroke
				(width 0.15)
				(type solid)
			)
			(layer "F.Fab")
		)
		(fp_line
			(start 0.504 0.248)
			(end -0.494 0.248)
			(stroke
				(width 0.15)
				(type solid)
			)
			(layer "F.Fab")
		)
		(fp_line
			(start -0.494 -0.25)
			(end 0.504 -0.25)
			(stroke
				(width 0.15)
				(type solid)
			)
			(layer "F.Fab")
		)
		(fp_line
			(start 0.504 -0.25)
			(end 0.504 0.248)
			(stroke
				(width 0.15)
				(type solid)
			)
			(layer "F.Fab")
		)
		(pad "1" smd roundrect
			(at -0.48 0 270)
			(size 0.59 0.64)
			(layers "F.Cu" "F.Mask" "F.Paste")
			(roundrect_rratio 0.25)
			(net 1 "GND")
			(pintype "passive")
		)
		(pad "2" smd roundrect
			(at 0.48 0 270)
			(size 0.59 0.64)
			(layers "F.Cu" "F.Mask" "F.Paste")
			(roundrect_rratio 0.25)
			(net 712 "/USB PHY/FTDI_VCORE")
			(pintype "passive")
		)
	)
	(footprint "antmicro-footprints:R_0402_1005Metric"
		(layer "F.Cu")
		(at 218.8 158.95)
		(descr "Resistor SMD 0402")
		(tags "resistor SMD 0402")
		(property "Reference" "R11"
			(at -2.85 0.4 0)
			(layer "F.SilkS")
			(effects
				(font
					(size 0.7 0.7)
					(thickness 0.15)
				)
				(justify left bottom)
			)
		)
		(property "Value" "R_10k_0402"
			(at 0 1.4 0)
			(layer "F.Fab")
			(effects
				(font
					(size 0.7 0.7)
					(thickness 0.15)
				)
				(justify left bottom)
			)
		)
		(property "Description" "SMD Chip Resistor, 10 kohm, ± 1%, 62.5 mW, 0402 [1005 Metric], Thick Film, General Purpose"
			(at 0 0 0)
			(layer "F.Fab")
			(hide yes)
			(effects
				(font
					(size 1.27 1.27)
					(thickness 0.15)
				)
			)
		)
		(property "Author" "Antmicro"
			(at 0 0 0)
			(layer "F.Fab")
			(hide yes)
			(effects
				(font
					(size 1 1)
					(thickness 0.15)
				)
			)
		)
		(property "License" "Apache-2.0"
			(at 0 0 0)
			(layer "F.Fab")
			(hide yes)
			(effects
				(font
					(size 1 1)
					(thickness 0.15)
				)
			)
		)
		(property "MPN" "CR0402-FX-1002GLF"
			(at 0 0 0)
			(layer "F.Fab")
			(hide yes)
			(effects
				(font
					(size 1 1)
					(thickness 0.15)
				)
			)
		)
		(property "Manufacturer" "Bourns"
			(at 0 0 0)
			(layer "F.Fab")
			(hide yes)
			(effects
				(font
					(size 1 1)
					(thickness 0.15)
				)
			)
		)
		(property "Tolerance" "1%"
			(at 0 0 0)
			(layer "F.Fab")
			(hide yes)
			(effects
				(font
					(size 1 1)
					(thickness 0.15)
				)
			)
		)
		(property "Val" "10k"
			(at 0 0 0)
			(layer "F.Fab")
			(hide yes)
			(effects
				(font
					(size 1 1)
					(thickness 0.15)
				)
			)
		)
		(sheetname "FPGA Config")
		(sheetfile "fpga-config.kicad_sch")
		(attr smd)
		(fp_rect
			(start -0.925 -0.47)
			(end 0.925 0.47)
			(stroke
				(width 0.05)
				(type default)
			)
			(fill no)
			(layer "F.CrtYd")
		)
		(fp_rect
			(start -0.5 -0.25)
			(end 0.5 0.25)
			(stroke
				(width 0.15)
				(type solid)
			)
			(fill no)
			(layer "F.Fab")
		)
		(pad "1" smd roundrect
			(at -0.48 0)
			(size 0.59 0.64)
			(layers "F.Cu" "F.Mask" "F.Paste")
			(roundrect_rratio 0.25)
			(net 113 "/FPGA Config/TEMP_~{ALERT}")
			(pintype "passive")
		)
		(pad "2" smd roundrect
			(at 0.48 0)
			(size 0.59 0.64)
			(layers "F.Cu" "F.Mask" "F.Paste")
			(roundrect_rratio 0.25)
			(net 24 "+3V3")
			(pintype "passive")
		)
	)
	(footprint "antmicro-footprints:C_0402_1005Metric"
		(layer "F.Cu")
		(at 174.030001 131.000001 90)
		(descr "Capacitor SMD 0402")
		(tags "capacitor SMD 0402")
		(property "Reference" "C308"
			(at -3.699999 0.369999 90)
			(layer "F.SilkS")
			(effects
				(font
					(size 0.7 0.7)
					(thickness 0.15)
				)
				(justify left bottom)
			)
		)
		(property "Value" "C_100n_0402"
			(at 0 1.4 90)
			(layer "F.Fab")
			(effects
				(font
					(size 0.7 0.7)
					(thickness 0.15)
				)
				(justify left bottom)
			)
		)
		(property "Description" "SMD Multilayer Ceramic Capacitor, 0.1 µF, 50 V, 0402 [1005 Metric], ± 10%, X5R, GRM Series"
			(at 0 0 90)
			(layer "F.Fab")
			(hide yes)
			(effects
				(font
					(size 1.27 1.27)
					(thickness 0.15)
				)
			)
		)
		(property "Author" "Antmicro"
			(at 305.030002 -43.03 0)
			(layer "F.Fab")
			(hide yes)
			(effects
				(font
					(size 1 1)
					(thickness 0.15)
				)
			)
		)
		(property "Dielectric" "X5R"
			(at 305.030002 -43.03 0)
			(layer "F.Fab")
			(hide yes)
			(effects
				(font
					(size 1 1)
					(thickness 0.15)
				)
			)
		)
		(property "License" "Apache-2.0"
			(at 305.030002 -43.03 0)
			(layer "F.Fab")
			(hide yes)
			(effects
				(font
					(size 1 1)
					(thickness 0.15)
				)
			)
		)
		(property "MPN" "GRM155R61H104KE14D"
			(at 305.030002 -43.03 0)
			(layer "F.Fab")
			(hide yes)
			(effects
				(font
					(size 1 1)
					(thickness 0.15)
				)
			)
		)
		(property "Manufacturer" "Murata"
			(at 305.030002 -43.03 0)
			(layer "F.Fab")
			(hide yes)
			(effects
				(font
					(size 1 1)
					(thickness 0.15)
				)
			)
		)
		(property "Val" "100n"
			(at 305.030002 -43.03 0)
			(layer "F.Fab")
			(hide yes)
			(effects
				(font
					(size 1 1)
					(thickness 0.15)
				)
			)
		)
		(property "Voltage" "50V"
			(at 305.030002 -43.03 0)
			(layer "F.Fab")
			(hide yes)
			(effects
				(font
					(size 1 1)
					(thickness 0.15)
				)
			)
		)
		(sheetname "FMC+ HSPC")
		(sheetfile "fmc-hspc.kicad_sch")
		(attr smd)
		(fp_rect
			(start -0.925 -0.47)
			(end 0.925 0.47)
			(stroke
				(width 0.05)
				(type default)
			)
			(fill no)
			(layer "F.CrtYd")
		)
		(fp_line
			(start 0.504 -0.25)
			(end 0.504 0.248)
			(stroke
				(width 0.15)
				(type solid)
			)
			(layer "F.Fab")
		)
		(fp_line
			(start -0.494 -0.25)
			(end 0.504 -0.25)
			(stroke
				(width 0.15)
				(type solid)
			)
			(layer "F.Fab")
		)
		(fp_line
			(start 0.504 0.248)
			(end -0.494 0.248)
			(stroke
				(width 0.15)
				(type solid)
			)
			(layer "F.Fab")
		)
		(fp_line
			(start -0.494 0.248)
			(end -0.494 -0.25)
			(stroke
				(width 0.15)
				(type solid)
			)
			(layer "F.Fab")
		)
		(pad "1" smd roundrect
			(at -0.48 0 90)
			(size 0.59 0.64)
			(layers "F.Cu" "F.Mask" "F.Paste")
			(roundrect_rratio 0.25)
			(net 97 "/FMC+ HSPC/GTX115.TX2_P")
			(pintype "passive")
		)
		(pad "2" smd roundrect
			(at 0.48 0 90)
			(size 0.59 0.64)
			(layers "F.Cu" "F.Mask" "F.Paste")
			(roundrect_rratio 0.25)
			(net 96 "/FMC+ HSPC/GTX_TX5_C_P")
			(pintype "passive")
		)
	)
	(footprint "antmicro-footprints:R_0402_1005Metric"
		(layer "F.Cu")
		(at 242.15 108.5)
		(descr "Resistor SMD 0402")
		(tags "resistor SMD 0402")
		(property "Reference" "R261"
			(at -3.65 0.35 0)
			(layer "F.SilkS")
			(effects
				(font
					(size 0.7 0.7)
					(thickness 0.15)
				)
				(justify left bottom)
			)
		)
		(property "Value" "R_0R_0402"
			(at 0 1.4 0)
			(layer "F.Fab")
			(effects
				(font
					(size 0.7 0.7)
					(thickness 0.15)
				)
				(justify left bottom)
			)
		)
		(property "Description" "SMD Chip Resistor, Jumper, 0 ohm, 100 mW, 0402 [1005 Metric], Thick Film, General Purpose"
			(at 0 0 0)
			(layer "F.Fab")
			(hide yes)
			(effects
				(font
					(size 1.27 1.27)
					(thickness 0.15)
				)
			)
		)
		(property "Author" "Antmicro"
			(at 0 0 0)
			(layer "F.Fab")
			(hide yes)
			(effects
				(font
					(size 1 1)
					(thickness 0.15)
				)
			)
		)
		(property "Current" "1A"
			(at 0 0 0)
			(layer "F.Fab")
			(hide yes)
			(effects
				(font
					(size 1 1)
					(thickness 0.15)
				)
			)
		)
		(property "License" "Apache-2.0"
			(at 0 0 0)
			(layer "F.Fab")
			(hide yes)
			(effects
				(font
					(size 1 1)
					(thickness 0.15)
				)
			)
		)
		(property "MPN" "ERJ2GE0R00X"
			(at 0 0 0)
			(layer "F.Fab")
			(hide yes)
			(effects
				(font
					(size 1 1)
					(thickness 0.15)
				)
			)
		)
		(property "Manufacturer" "Panasonic"
			(at 0 0 0)
			(layer "F.Fab")
			(hide yes)
			(effects
				(font
					(size 1 1)
					(thickness 0.15)
				)
			)
		)
		(property "Tolerance" ""
			(at 0 0 0)
			(layer "F.Fab")
			(hide yes)
			(effects
				(font
					(size 1 1)
					(thickness 0.15)
				)
			)
		)
		(property "Val" "0R"
			(at 0 0 0)
			(layer "F.Fab")
			(hide yes)
			(effects
				(font
					(size 1 1)
					(thickness 0.15)
				)
			)
		)
		(sheetname "HDMI + Ethernet")
		(sheetfile "hdmi-ethernet.kicad_sch")
		(attr smd)
		(fp_rect
			(start -0.925 -0.47)
			(end 0.925 0.47)
			(stroke
				(width 0.05)
				(type default)
			)
			(fill no)
			(layer "F.CrtYd")
		)
		(fp_rect
			(start -0.5 -0.25)
			(end 0.5 0.25)
			(stroke
				(width 0.15)
				(type solid)
			)
			(fill no)
			(layer "F.Fab")
		)
		(pad "1" smd roundrect
			(at -0.48 0)
			(size 0.59 0.64)
			(layers "F.Cu" "F.Mask" "F.Paste")
			(roundrect_rratio 0.25)
			(net 565 "/FPGA Bank 16 & 17/HDMI.CLK_N")
			(pintype "passive")
		)
		(pad "2" smd roundrect
			(at 0.48 0)
			(size 0.59 0.64)
			(layers "F.Cu" "F.Mask" "F.Paste")
			(roundrect_rratio 0.25)
			(net 868 "/HDMI + Ethernet/HDMI_CONN_CLK_N")
			(pintype "passive")
		)
	)
)
